(kicad_pcb
	(version 20260206)
	(generator "pcbnew")
	(generator_version "10.0")
	(general
		(thickness 1.6)
		(legacy_teardrops no)
	)
	(paper "A4")
	(title_block
		(title "12092022_DA0F0TYB4D0_F0T_Panel_BD_Front_D_brd_v02_OCP.brd")
		(comment 1 "Grand Teton / footprints 28-33 of 128")
	)
	(layers
		(0 "F.Cu" signal "TOP")
		(4 "In1.Cu" signal "GND")
		(6 "In2.Cu" signal "GND1")
		(2 "B.Cu" signal "BOTTOM")
		(9 "F.Adhes" user "F.Adhesive")
		(11 "B.Adhes" user "B.Adhesive")
		(13 "F.Paste" user "Package Geometry/Pastemask Top")
		(15 "B.Paste" user "Package Geometry/Pastemask Bottom")
		(5 "F.SilkS" user "Ref Des/Silkscreen Top")
		(7 "B.SilkS" user "Ref Des/Silkscreen Bottom")
		(1 "F.Mask" user "Board Geometry/Soldermask Top")
		(3 "B.Mask" user "Board Geometry/Soldermask Bottom")
		(17 "Dwgs.User" user "User.Drawings")
		(19 "Cmts.User" user "User.Comments")
		(21 "Eco1.User" user "User.Eco1")
		(23 "Eco2.User" user "User.Eco2")
		(25 "Edge.Cuts" user "Board Geometry/Outline")
		(27 "Margin" user)
		(31 "F.CrtYd" user "Package Geometry/Place Bound Top")
		(29 "B.CrtYd" user "Package Geometry/Place Bound Bottom")
		(35 "F.Fab" user "Ref Des/Assembly Top")
		(33 "B.Fab" user "Ref Des/Assembly Bottom")
	)
	(footprint ""
		(layer "F.Cu")
		(at 15.875 -45.085 180)
		(property "Reference" "R54"
			(at -2.54 -0.02667 0)
			(unlocked yes)
			(layer "F.SilkS")
			(effects
				(font
					(size 0.7874 0.5842)
					(thickness 0.1524)
				)
			)
		)
		(property "Value" ""
			(at 0 0 180)
			(layer "F.Fab")
			(effects
				(font
					(size 1.27 1.27)
				)
			)
		)
		(duplicate_pad_numbers_are_jumpers no)
		(fp_line
			(start 0.7874 0.4064)
			(end -0.7874 0.4064)
			(stroke
				(width 0.1524)
				(type default)
			)
			(layer "F.SilkS")
		)
		(fp_line
			(start 0.7874 -0.4064)
			(end 0.7874 0.4064)
			(stroke
				(width 0.1524)
				(type default)
			)
			(layer "F.SilkS")
		)
		(fp_line
			(start -0.7874 0.4064)
			(end -0.7874 -0.4064)
			(stroke
				(width 0.1524)
				(type default)
			)
			(layer "F.SilkS")
		)
		(fp_line
			(start -0.7874 -0.4064)
			(end 0.7874 -0.4064)
			(stroke
				(width 0.1524)
				(type default)
			)
			(layer "F.SilkS")
		)
		(fp_line
			(start 0.67945 0.3048)
			(end 0.120396 0.3048)
			(stroke
				(width 0.1)
				(type default)
			)
			(layer "F.Fab")
		)
		(fp_line
			(start 0.67945 -0.3048)
			(end 0.67945 0.3048)
			(stroke
				(width 0.1)
				(type default)
			)
			(layer "F.Fab")
		)
		(fp_line
			(start 0.12065 -0.2794)
			(end 0.12065 -0.3048)
			(stroke
				(width 0.1)
				(type default)
			)
			(layer "F.Fab")
		)
		(fp_line
			(start 0.12065 -0.3048)
			(end 0.67945 -0.3048)
			(stroke
				(width 0.1)
				(type default)
			)
			(layer "F.Fab")
		)
		(fp_line
			(start 0.120396 0.3048)
			(end 0.120396 0.2794)
			(stroke
				(width 0.1)
				(type default)
			)
			(layer "F.Fab")
		)
		(fp_line
			(start 0.120396 0.2794)
			(end -0.12065 0.2794)
			(stroke
				(width 0.1)
				(type default)
			)
			(layer "F.Fab")
		)
		(fp_line
			(start -0.12065 0.3048)
			(end -0.67945 0.3048)
			(stroke
				(width 0.1)
				(type default)
			)
			(layer "F.Fab")
		)
		(fp_line
			(start -0.12065 0.2794)
			(end -0.12065 0.3048)
			(stroke
				(width 0.1)
				(type default)
			)
			(layer "F.Fab")
		)
		(fp_line
			(start -0.12065 -0.2794)
			(end 0.12065 -0.2794)
			(stroke
				(width 0.1)
				(type default)
			)
			(layer "F.Fab")
		)
		(fp_line
			(start -0.12065 -0.305054)
			(end -0.12065 -0.2794)
			(stroke
				(width 0.1)
				(type default)
			)
			(layer "F.Fab")
		)
		(fp_line
			(start -0.67945 0.3048)
			(end -0.67945 -0.305054)
			(stroke
				(width 0.1)
				(type default)
			)
			(layer "F.Fab")
		)
		(fp_line
			(start -0.67945 -0.305054)
			(end -0.12065 -0.305054)
			(stroke
				(width 0.1)
				(type default)
			)
			(layer "F.Fab")
		)
		(pad "1" smd circle
			(at -0.40005 0 180)
			(size 0 0)
			(layers "F.Cu" "F.Mask" "F.Paste")
			(net "P3V3_STBY")
		)
		(pad "2" smd circle
			(at 0.40005 0 180)
			(size 0 0)
			(layers "F.Cu" "F.Mask" "F.Paste")
			(net "SMB_FRU_SDA")
		)
	)
	(footprint ""
		(layer "F.Cu")
		(at 18.415 -59.817 180)
		(property "Reference" "R16"
			(at -3.81 -0.02667 0)
			(unlocked yes)
			(layer "F.SilkS")
			(effects
				(font
					(size 0.7874 0.5842)
					(thickness 0.1524)
				)
			)
		)
		(property "Value" ""
			(at 0 0 180)
			(layer "F.Fab")
			(effects
				(font
					(size 1.27 1.27)
				)
			)
		)
		(duplicate_pad_numbers_are_jumpers no)
		(fp_line
			(start 0.7874 0.4064)
			(end -0.7874 0.4064)
			(stroke
				(width 0.1524)
				(type default)
			)
			(layer "F.SilkS")
		)
		(fp_line
			(start 0.7874 -0.4064)
			(end 0.7874 0.4064)
			(stroke
				(width 0.1524)
				(type default)
			)
			(layer "F.SilkS")
		)
		(fp_line
			(start -0.7874 0.4064)
			(end -0.7874 -0.4064)
			(stroke
				(width 0.1524)
				(type default)
			)
			(layer "F.SilkS")
		)
		(fp_line
			(start -0.7874 -0.4064)
			(end 0.7874 -0.4064)
			(stroke
				(width 0.1524)
				(type default)
			)
			(layer "F.SilkS")
		)
		(fp_line
			(start 0.67945 0.3048)
			(end 0.120396 0.3048)
			(stroke
				(width 0.1)
				(type default)
			)
			(layer "F.Fab")
		)
		(fp_line
			(start 0.67945 -0.3048)
			(end 0.67945 0.3048)
			(stroke
				(width 0.1)
				(type default)
			)
			(layer "F.Fab")
		)
		(fp_line
			(start 0.12065 -0.2794)
			(end 0.12065 -0.3048)
			(stroke
				(width 0.1)
				(type default)
			)
			(layer "F.Fab")
		)
		(fp_line
			(start 0.12065 -0.3048)
			(end 0.67945 -0.3048)
			(stroke
				(width 0.1)
				(type default)
			)
			(layer "F.Fab")
		)
		(fp_line
			(start 0.120396 0.3048)
			(end 0.120396 0.2794)
			(stroke
				(width 0.1)
				(type default)
			)
			(layer "F.Fab")
		)
		(fp_line
			(start 0.120396 0.2794)
			(end -0.12065 0.2794)
			(stroke
				(width 0.1)
				(type default)
			)
			(layer "F.Fab")
		)
		(fp_line
			(start -0.12065 0.3048)
			(end -0.67945 0.3048)
			(stroke
				(width 0.1)
				(type default)
			)
			(layer "F.Fab")
		)
		(fp_line
			(start -0.12065 0.2794)
			(end -0.12065 0.3048)
			(stroke
				(width 0.1)
				(type default)
			)
			(layer "F.Fab")
		)
		(fp_line
			(start -0.12065 -0.2794)
			(end 0.12065 -0.2794)
			(stroke
				(width 0.1)
				(type default)
			)
			(layer "F.Fab")
		)
		(fp_line
			(start -0.12065 -0.305054)
			(end -0.12065 -0.2794)
			(stroke
				(width 0.1)
				(type default)
			)
			(layer "F.Fab")
		)
		(fp_line
			(start -0.67945 0.3048)
			(end -0.67945 -0.305054)
			(stroke
				(width 0.1)
				(type default)
			)
			(layer "F.Fab")
		)
		(fp_line
			(start -0.67945 -0.305054)
			(end -0.12065 -0.305054)
			(stroke
				(width 0.1)
				(type default)
			)
			(layer "F.Fab")
		)
		(pad "1" smd circle
			(at -0.40005 0 180)
			(size 0 0)
			(layers "F.Cu" "F.Mask" "F.Paste")
			(net "SMB_SCL")
		)
		(pad "2" smd circle
			(at 0.40005 0 180)
			(size 0 0)
			(layers "F.Cu" "F.Mask" "F.Paste")
			(net "SMB_EXP_SCL")
		)
	)
	(footprint ""
		(layer "F.Cu")
		(at 15.875 -50.165)
		(property "Reference" "R64"
			(at 2.54 0.02667 0)
			(unlocked yes)
			(layer "F.SilkS")
			(effects
				(font
					(size 0.7874 0.5842)
					(thickness 0.1524)
				)
			)
		)
		(property "Value" ""
			(at 0 0 0)
			(layer "F.Fab")
			(effects
				(font
					(size 1.27 1.27)
				)
			)
		)
		(duplicate_pad_numbers_are_jumpers no)
		(fp_line
			(start -0.7874 -0.4064)
			(end 0.7874 -0.4064)
			(stroke
				(width 0.1524)
				(type default)
			)
			(layer "F.SilkS")
		)
		(fp_line
			(start -0.7874 0.4064)
			(end -0.7874 -0.4064)
			(stroke
				(width 0.1524)
				(type default)
			)
			(layer "F.SilkS")
		)
		(fp_line
			(start 0.7874 -0.4064)
			(end 0.7874 0.4064)
			(stroke
				(width 0.1524)
				(type default)
			)
			(layer "F.SilkS")
		)
		(fp_line
			(start 0.7874 0.4064)
			(end -0.7874 0.4064)
			(stroke
				(width 0.1524)
				(type default)
			)
			(layer "F.SilkS")
		)
		(fp_line
			(start -0.67945 -0.305054)
			(end -0.12065 -0.305054)
			(stroke
				(width 0.1)
				(type default)
			)
			(layer "F.Fab")
		)
		(fp_line
			(start -0.67945 0.3048)
			(end -0.67945 -0.305054)
			(stroke
				(width 0.1)
				(type default)
			)
			(layer "F.Fab")
		)
		(fp_line
			(start -0.12065 -0.305054)
			(end -0.12065 -0.2794)
			(stroke
				(width 0.1)
				(type default)
			)
			(layer "F.Fab")
		)
		(fp_line
			(start -0.12065 -0.2794)
			(end 0.12065 -0.2794)
			(stroke
				(width 0.1)
				(type default)
			)
			(layer "F.Fab")
		)
		(fp_line
			(start -0.12065 0.2794)
			(end -0.12065 0.3048)
			(stroke
				(width 0.1)
				(type default)
			)
			(layer "F.Fab")
		)
		(fp_line
			(start -0.12065 0.3048)
			(end -0.67945 0.3048)
			(stroke
				(width 0.1)
				(type default)
			)
			(layer "F.Fab")
		)
		(fp_line
			(start 0.120396 0.2794)
			(end -0.12065 0.2794)
			(stroke
				(width 0.1)
				(type default)
			)
			(layer "F.Fab")
		)
		(fp_line
			(start 0.120396 0.3048)
			(end 0.120396 0.2794)
			(stroke
				(width 0.1)
				(type default)
			)
			(layer "F.Fab")
		)
		(fp_line
			(start 0.12065 -0.3048)
			(end 0.67945 -0.3048)
			(stroke
				(width 0.1)
				(type default)
			)
			(layer "F.Fab")
		)
		(fp_line
			(start 0.12065 -0.2794)
			(end 0.12065 -0.3048)
			(stroke
				(width 0.1)
				(type default)
			)
			(layer "F.Fab")
		)
		(fp_line
			(start 0.67945 -0.3048)
			(end 0.67945 0.3048)
			(stroke
				(width 0.1)
				(type default)
			)
			(layer "F.Fab")
		)
		(fp_line
			(start 0.67945 0.3048)
			(end 0.120396 0.3048)
			(stroke
				(width 0.1)
				(type default)
			)
			(layer "F.Fab")
		)
		(pad "1" smd circle
			(at -0.40005 0)
			(size 0 0)
			(layers "F.Cu" "F.Mask" "F.Paste")
			(net "PD_FRU_WP")
		)
		(pad "2" smd circle
			(at 0.40005 0)
			(size 0 0)
			(layers "F.Cu" "F.Mask" "F.Paste")
			(net "GND")
		)
	)
	(footprint ""
		(layer "F.Cu")
		(at 3.937 -50.8)
		(property "Reference" "R63"
			(at -2.413 0.15367 0)
			(unlocked yes)
			(layer "F.SilkS")
			(effects
				(font
					(size 0.7874 0.5842)
					(thickness 0.1524)
				)
			)
		)
		(property "Value" ""
			(at 0 0 0)
			(layer "F.Fab")
			(effects
				(font
					(size 1.27 1.27)
				)
			)
		)
		(duplicate_pad_numbers_are_jumpers no)
		(fp_line
			(start -0.7874 -0.4064)
			(end 0.7874 -0.4064)
			(stroke
				(width 0.1524)
				(type default)
			)
			(layer "F.SilkS")
		)
		(fp_line
			(start -0.7874 0.4064)
			(end -0.7874 -0.4064)
			(stroke
				(width 0.1524)
				(type default)
			)
			(layer "F.SilkS")
		)
		(fp_line
			(start 0.7874 -0.4064)
			(end 0.7874 0.4064)
			(stroke
				(width 0.1524)
				(type default)
			)
			(layer "F.SilkS")
		)
		(fp_line
			(start 0.7874 0.4064)
			(end -0.7874 0.4064)
			(stroke
				(width 0.1524)
				(type default)
			)
			(layer "F.SilkS")
		)
		(fp_line
			(start -0.67945 -0.305054)
			(end -0.12065 -0.305054)
			(stroke
				(width 0.1)
				(type default)
			)
			(layer "F.Fab")
		)
		(fp_line
			(start -0.67945 0.3048)
			(end -0.67945 -0.305054)
			(stroke
				(width 0.1)
				(type default)
			)
			(layer "F.Fab")
		)
		(fp_line
			(start -0.12065 -0.305054)
			(end -0.12065 -0.2794)
			(stroke
				(width 0.1)
				(type default)
			)
			(layer "F.Fab")
		)
		(fp_line
			(start -0.12065 -0.2794)
			(end 0.12065 -0.2794)
			(stroke
				(width 0.1)
				(type default)
			)
			(layer "F.Fab")
		)
		(fp_line
			(start -0.12065 0.2794)
			(end -0.12065 0.3048)
			(stroke
				(width 0.1)
				(type default)
			)
			(layer "F.Fab")
		)
		(fp_line
			(start -0.12065 0.3048)
			(end -0.67945 0.3048)
			(stroke
				(width 0.1)
				(type default)
			)
			(layer "F.Fab")
		)
		(fp_line
			(start 0.120396 0.2794)
			(end -0.12065 0.2794)
			(stroke
				(width 0.1)
				(type default)
			)
			(layer "F.Fab")
		)
		(fp_line
			(start 0.120396 0.3048)
			(end 0.120396 0.2794)
			(stroke
				(width 0.1)
				(type default)
			)
			(layer "F.Fab")
		)
		(fp_line
			(start 0.12065 -0.3048)
			(end 0.67945 -0.3048)
			(stroke
				(width 0.1)
				(type default)
			)
			(layer "F.Fab")
		)
		(fp_line
			(start 0.12065 -0.2794)
			(end 0.12065 -0.3048)
			(stroke
				(width 0.1)
				(type default)
			)
			(layer "F.Fab")
		)
		(fp_line
			(start 0.67945 -0.3048)
			(end 0.67945 0.3048)
			(stroke
				(width 0.1)
				(type default)
			)
			(layer "F.Fab")
		)
		(fp_line
			(start 0.67945 0.3048)
			(end 0.120396 0.3048)
			(stroke
				(width 0.1)
				(type default)
			)
			(layer "F.Fab")
		)
		(pad "1" smd circle
			(at -0.40005 0)
			(size 0 0)
			(layers "F.Cu" "F.Mask" "F.Paste")
			(net "GND")
		)
		(pad "2" smd circle
			(at 0.40005 0)
			(size 0 0)
			(layers "F.Cu" "F.Mask" "F.Paste")
			(net "PD_FRU_A0")
		)
	)
	(footprint ""
		(layer "F.Cu")
		(at 21.717 -63.373 -90)
		(property "Reference" "R67"
			(at -0.254 -2.31267 90)
			(unlocked yes)
			(layer "F.SilkS")
			(effects
				(font
					(size 0.7874 0.5842)
					(thickness 0.1524)
				)
			)
		)
		(property "Value" ""
			(at 0 0 270)
			(layer "F.Fab")
			(effects
				(font
					(size 1.27 1.27)
				)
			)
		)
		(duplicate_pad_numbers_are_jumpers no)
		(fp_line
			(start -0.7874 0.4064)
			(end -0.7874 -0.4064)
			(stroke
				(width 0.1524)
				(type default)
			)
			(layer "F.SilkS")
		)
		(fp_line
			(start 0.7874 0.4064)
			(end -0.7874 0.4064)
			(stroke
				(width 0.1524)
				(type default)
			)
			(layer "F.SilkS")
		)
		(fp_line
			(start -0.7874 -0.4064)
			(end 0.7874 -0.4064)
			(stroke
				(width 0.1524)
				(type default)
			)
			(layer "F.SilkS")
		)
		(fp_line
			(start 0.7874 -0.4064)
			(end 0.7874 0.4064)
			(stroke
				(width 0.1524)
				(type default)
			)
			(layer "F.SilkS")
		)
		(fp_line
			(start -0.67945 0.3048)
			(end -0.67945 -0.305054)
			(stroke
				(width 0.1)
				(type default)
			)
			(layer "F.Fab")
		)
		(fp_line
			(start -0.12065 0.3048)
			(end -0.67945 0.3048)
			(stroke
				(width 0.1)
				(type default)
			)
			(layer "F.Fab")
		)
		(fp_line
			(start 0.120396 0.3048)
			(end 0.120396 0.2794)
			(stroke
				(width 0.1)
				(type default)
			)
			(layer "F.Fab")
		)
		(fp_line
			(start 0.67945 0.3048)
			(end 0.120396 0.3048)
			(stroke
				(width 0.1)
				(type default)
			)
			(layer "F.Fab")
		)
		(fp_line
			(start -0.12065 0.2794)
			(end -0.12065 0.3048)
			(stroke
				(width 0.1)
				(type default)
			)
			(layer "F.Fab")
		)
		(fp_line
			(start 0.120396 0.2794)
			(end -0.12065 0.2794)
			(stroke
				(width 0.1)
				(type default)
			)
			(layer "F.Fab")
		)
		(fp_line
			(start -0.12065 -0.2794)
			(end 0.12065 -0.2794)
			(stroke
				(width 0.1)
				(type default)
			)
			(layer "F.Fab")
		)
		(fp_line
			(start 0.12065 -0.2794)
			(end 0.12065 -0.3048)
			(stroke
				(width 0.1)
				(type default)
			)
			(layer "F.Fab")
		)
		(fp_line
			(start 0.12065 -0.3048)
			(end 0.67945 -0.3048)
			(stroke
				(width 0.1)
				(type default)
			)
			(layer "F.Fab")
		)
		(fp_line
			(start 0.67945 -0.3048)
			(end 0.67945 0.3048)
			(stroke
				(width 0.1)
				(type default)
			)
			(layer "F.Fab")
		)
		(fp_line
			(start -0.67945 -0.305054)
			(end -0.12065 -0.305054)
			(stroke
				(width 0.1)
				(type default)
			)
			(layer "F.Fab")
		)
		(fp_line
			(start -0.12065 -0.305054)
			(end -0.12065 -0.2794)
			(stroke
				(width 0.1)
				(type default)
			)
			(layer "F.Fab")
		)
		(pad "1" smd circle
			(at -0.40005 0 270)
			(size 0 0)
			(layers "F.Cu" "F.Mask" "F.Paste")
			(net "SMB_SWB_SCL")
		)
		(pad "2" smd circle
			(at 0.40005 0 270)
			(size 0 0)
			(layers "F.Cu" "F.Mask" "F.Paste")
			(net "SMB_SCL")
		)
	)
	(footprint ""
		(layer "F.Cu")
		(at 36.703 -27.432 180)
		(property "Reference" "R41"
			(at 7.874 0.35433 0)
			(unlocked yes)
			(layer "F.SilkS")
			(effects
				(font
					(size 0.7874 0.5842)
					(thickness 0.1524)
				)
			)
		)
		(property "Value" ""
			(at 0 0 180)
			(layer "F.Fab")
			(effects
				(font
					(size 1.27 1.27)
				)
			)
		)
		(duplicate_pad_numbers_are_jumpers no)
		(fp_line
			(start 0.7874 0.4064)
			(end -0.7874 0.4064)
			(stroke
				(width 0.1524)
				(type default)
			)
			(layer "F.SilkS")
		)
		(fp_line
			(start 0.7874 -0.4064)
			(end 0.7874 0.4064)
			(stroke
				(width 0.1524)
				(type default)
			)
			(layer "F.SilkS")
		)
		(fp_line
			(start -0.7874 0.4064)
			(end -0.7874 -0.4064)
			(stroke
				(width 0.1524)
				(type default)
			)
			(layer "F.SilkS")
		)
		(fp_line
			(start -0.7874 -0.4064)
			(end 0.7874 -0.4064)
			(stroke
				(width 0.1524)
				(type default)
			)
			(layer "F.SilkS")
		)
		(fp_line
			(start 0.67945 0.3048)
			(end 0.120396 0.3048)
			(stroke
				(width 0.1)
				(type default)
			)
			(layer "F.Fab")
		)
		(fp_line
			(start 0.67945 -0.3048)
			(end 0.67945 0.3048)
			(stroke
				(width 0.1)
				(type default)
			)
			(layer "F.Fab")
		)
		(fp_line
			(start 0.12065 -0.2794)
			(end 0.12065 -0.3048)
			(stroke
				(width 0.1)
				(type default)
			)
			(layer "F.Fab")
		)
		(fp_line
			(start 0.12065 -0.3048)
			(end 0.67945 -0.3048)
			(stroke
				(width 0.1)
				(type default)
			)
			(layer "F.Fab")
		)
		(fp_line
			(start 0.120396 0.3048)
			(end 0.120396 0.2794)
			(stroke
				(width 0.1)
				(type default)
			)
			(layer "F.Fab")
		)
		(fp_line
			(start 0.120396 0.2794)
			(end -0.12065 0.2794)
			(stroke
				(width 0.1)
				(type default)
			)
			(layer "F.Fab")
		)
		(fp_line
			(start -0.12065 0.3048)
			(end -0.67945 0.3048)
			(stroke
				(width 0.1)
				(type default)
			)
			(layer "F.Fab")
		)
		(fp_line
			(start -0.12065 0.2794)
			(end -0.12065 0.3048)
			(stroke
				(width 0.1)
				(type default)
			)
			(layer "F.Fab")
		)
		(fp_line
			(start -0.12065 -0.2794)
			(end 0.12065 -0.2794)
			(stroke
				(width 0.1)
				(type default)
			)
			(layer "F.Fab")
		)
		(fp_line
			(start -0.12065 -0.305054)
			(end -0.12065 -0.2794)
			(stroke
				(width 0.1)
				(type default)
			)
			(layer "F.Fab")
		)
		(fp_line
			(start -0.67945 0.3048)
			(end -0.67945 -0.305054)
			(stroke
				(width 0.1)
				(type default)
			)
			(layer "F.Fab")
		)
		(fp_line
			(start -0.67945 -0.305054)
			(end -0.12065 -0.305054)
			(stroke
				(width 0.1)
				(type default)
			)
			(layer "F.Fab")
		)
		(pad "1" smd circle
			(at -0.40005 0 180)
			(size 0 0)
			(layers "F.Cu" "F.Mask" "F.Paste")
			(net "P3V3_STBY")
		)
		(pad "2" smd circle
			(at 0.40005 0 180)
			(size 0 0)
			(layers "F.Cu" "F.Mask" "F.Paste")
			(net "NCP380_FLT_N")
		)
	)
)
